# S9S_MB_2U (Grand Teton) — schematic netlist excerpt (pin names and nets, part order shuffled) for the footprints in the layout excerpt that follows; sources: Cadence DE-HDL packaged netlist, KiCad conversion of 03242023_DA0F0TMBIJ0_F0T_Motherboard_J_brd_V01_OCP.brd

PC2946  Q_CAP  2.2UF 10V 10% X6S  pkg C0402  page 275 : A = PVCCFA_EHV_CPU0_PVCC ; B = GND
PL4  Q_INDUCTOR  120NH/69A IND  pkg SMLF  page 275 : \1\ = SW_PVCCINFAON_CPU0_SW1 ; \2\ = PVCCINFAON_CPU0
R1332  Q_RES  4.7K 5% EMPTY  pkg 0402LF  page 243 : A = P3V3_AUX ; B = SMB_FRU_3V3AUX_SDA

(kicad_pcb
	(version 20260206)
	(generator "pcbnew")
	(generator_version "10.0")
	(general
		(thickness 1.6)
		(legacy_teardrops no)
	)
	(paper "A4")
	(title_block
		(title "03242023_DA0F0TMBIJ0_F0T_Motherboard_J_brd_V01_OCP.brd")
		(comment 1 "Grand Teton / footprints 2260-2262 of 6105")
	)
	(layers
		(0 "F.Cu" signal "TOP")
		(4 "In1.Cu" signal "GND")
		(6 "In2.Cu" signal "IN1")
		(8 "In3.Cu" signal "GND1")
		(10 "In4.Cu" signal "IN2")
		(12 "In5.Cu" signal "GND2")
		(14 "In6.Cu" signal "IN3")
		(16 "In7.Cu" signal "GND3")
		(18 "In8.Cu" signal "VCC")
		(20 "In9.Cu" signal "VCC1")
		(22 "In10.Cu" signal "GND4")
		(24 "In11.Cu" signal "IN4")
		(26 "In12.Cu" signal "GND5")
		(28 "In13.Cu" signal "IN5")
		(30 "In14.Cu" signal "GND6")
		(32 "In15.Cu" signal "IN6")
		(34 "In16.Cu" signal "GND7")
		(2 "B.Cu" signal "BOTTOM")
		(9 "F.Adhes" user "F.Adhesive")
		(11 "B.Adhes" user "B.Adhesive")
		(13 "F.Paste" user "Package Geometry/Pastemask Top")
		(15 "B.Paste" user "Package Geometry/Pastemask Bottom")
		(5 "F.SilkS" user "Ref Des/Silkscreen Top")
		(7 "B.SilkS" user "Ref Des/Silkscreen Bottom")
		(1 "F.Mask" user "Board Geometry/Soldermask Top")
		(3 "B.Mask" user "Board Geometry/Soldermask Bottom")
		(17 "Dwgs.User" user "User.Drawings")
		(19 "Cmts.User" user "User.Comments")
		(21 "Eco1.User" user "User.Eco1")
		(23 "Eco2.User" user "User.Eco2")
		(25 "Edge.Cuts" user "Board Geometry/Outline")
		(27 "Margin" user)
		(31 "F.CrtYd" user "Package Geometry/Place Bound Top")
		(29 "B.CrtYd" user "Package Geometry/Place Bound Bottom")
		(35 "F.Fab" user "Ref Des/Assembly Top")
		(33 "B.Fab" user "Ref Des/Assembly Bottom")
	)
	(footprint ""
		(layer "F.Cu")
		(at 292.62832 -92.260674 180)
		(property "Reference" "R1332"
			(at 0 0 180)
			(layer "F.SilkS")
			(hide yes)
			(effects
				(font
					(size 1.27 1.27)
				)
			)
		)
		(property "Value" ""
			(at 0 0 180)
			(layer "F.Fab")
			(effects
				(font
					(size 1.27 1.27)
				)
			)
		)
		(duplicate_pad_numbers_are_jumpers no)
		(fp_line
			(start 0.7874 0.4064)
			(end -0.7874 0.4064)
			(stroke
				(width 0.1524)
				(type default)
			)
			(layer "F.SilkS")
		)
		(fp_line
			(start 0.7874 -0.4064)
			(end 0.7874 0.4064)
			(stroke
				(width 0.1524)
				(type default)
			)
			(layer "F.SilkS")
		)
		(fp_line
			(start -0.7874 0.4064)
			(end -0.7874 -0.4064)
			(stroke
				(width 0.1524)
				(type default)
			)
			(layer "F.SilkS")
		)
		(fp_line
			(start -0.7874 -0.4064)
			(end 0.7874 -0.4064)
			(stroke
				(width 0.1524)
				(type default)
			)
			(layer "F.SilkS")
		)
		(fp_line
			(start 0.67945 0.3048)
			(end 0.120396 0.3048)
			(stroke
				(width 0.1)
				(type default)
			)
			(layer "F.Fab")
		)
		(fp_line
			(start 0.67945 -0.3048)
			(end 0.67945 0.3048)
			(stroke
				(width 0.1)
				(type default)
			)
			(layer "F.Fab")
		)
		(fp_line
			(start 0.12065 -0.2794)
			(end 0.12065 -0.3048)
			(stroke
				(width 0.1)
				(type default)
			)
			(layer "F.Fab")
		)
		(fp_line
			(start 0.12065 -0.3048)
			(end 0.67945 -0.3048)
			(stroke
				(width 0.1)
				(type default)
			)
			(layer "F.Fab")
		)
		(fp_line
			(start 0.120396 0.3048)
			(end 0.120396 0.2794)
			(stroke
				(width 0.1)
				(type default)
			)
			(layer "F.Fab")
		)
		(fp_line
			(start 0.120396 0.2794)
			(end -0.12065 0.2794)
			(stroke
				(width 0.1)
				(type default)
			)
			(layer "F.Fab")
		)
		(fp_line
			(start -0.12065 0.3048)
			(end -0.67945 0.3048)
			(stroke
				(width 0.1)
				(type default)
			)
			(layer "F.Fab")
		)
		(fp_line
			(start -0.12065 0.2794)
			(end -0.12065 0.3048)
			(stroke
				(width 0.1)
				(type default)
			)
			(layer "F.Fab")
		)
		(fp_line
			(start -0.12065 -0.2794)
			(end 0.12065 -0.2794)
			(stroke
				(width 0.1)
				(type default)
			)
			(layer "F.Fab")
		)
		(fp_line
			(start -0.12065 -0.305054)
			(end -0.12065 -0.2794)
			(stroke
				(width 0.1)
				(type default)
			)
			(layer "F.Fab")
		)
		(fp_line
			(start -0.67945 0.3048)
			(end -0.67945 -0.305054)
			(stroke
				(width 0.1)
				(type default)
			)
			(layer "F.Fab")
		)
		(fp_line
			(start -0.67945 -0.305054)
			(end -0.12065 -0.305054)
			(stroke
				(width 0.1)
				(type default)
			)
			(layer "F.Fab")
		)
		(pad "1" smd circle
			(at -0.40005 0 180)
			(size 0 0)
			(layers "F.Cu" "F.Mask" "F.Paste")
			(net "P3V3_AUX")
		)
		(pad "2" smd circle
			(at 0.40005 0 180)
			(size 0 0)
			(layers "F.Cu" "F.Mask" "F.Paste")
			(net "SMB_FRU_3V3AUX_SDA")
		)
	)
	(footprint ""
		(layer "F.Cu")
		(at 415.818828 -183.032654 180)
		(property "Reference" "PC2946"
			(at 0 0 180)
			(layer "F.SilkS")
			(hide yes)
			(effects
				(font
					(size 1.27 1.27)
				)
			)
		)
		(property "Value" ""
			(at 0 0 180)
			(layer "F.Fab")
			(effects
				(font
					(size 1.27 1.27)
				)
			)
		)
		(duplicate_pad_numbers_are_jumpers no)
		(fp_line
			(start 0.7874 0.4064)
			(end -0.7874 0.4064)
			(stroke
				(width 0.1524)
				(type default)
			)
			(layer "F.SilkS")
		)
		(fp_line
			(start 0.7874 -0.4064)
			(end 0.7874 0.4064)
			(stroke
				(width 0.1524)
				(type default)
			)
			(layer "F.SilkS")
		)
		(fp_line
			(start -0.7874 0.4064)
			(end -0.7874 -0.4064)
			(stroke
				(width 0.1524)
				(type default)
			)
			(layer "F.SilkS")
		)
		(fp_line
			(start -0.7874 -0.4064)
			(end 0.7874 -0.4064)
			(stroke
				(width 0.1524)
				(type default)
			)
			(layer "F.SilkS")
		)
		(fp_line
			(start 0.67945 0.3048)
			(end 0.120396 0.3048)
			(stroke
				(width 0.1)
				(type default)
			)
			(layer "F.Fab")
		)
		(fp_line
			(start 0.67945 -0.3048)
			(end 0.67945 0.3048)
			(stroke
				(width 0.1)
				(type default)
			)
			(layer "F.Fab")
		)
		(fp_line
			(start 0.12065 -0.2794)
			(end 0.12065 -0.3048)
			(stroke
				(width 0.1)
				(type default)
			)
			(layer "F.Fab")
		)
		(fp_line
			(start 0.12065 -0.3048)
			(end 0.67945 -0.3048)
			(stroke
				(width 0.1)
				(type default)
			)
			(layer "F.Fab")
		)
		(fp_line
			(start 0.120396 0.3048)
			(end 0.120396 0.2794)
			(stroke
				(width 0.1)
				(type default)
			)
			(layer "F.Fab")
		)
		(fp_line
			(start 0.120396 0.2794)
			(end -0.12065 0.2794)
			(stroke
				(width 0.1)
				(type default)
			)
			(layer "F.Fab")
		)
		(fp_line
			(start -0.12065 0.3048)
			(end -0.67945 0.3048)
			(stroke
				(width 0.1)
				(type default)
			)
			(layer "F.Fab")
		)
		(fp_line
			(start -0.12065 0.2794)
			(end -0.12065 0.3048)
			(stroke
				(width 0.1)
				(type default)
			)
			(layer "F.Fab")
		)
		(fp_line
			(start -0.12065 -0.2794)
			(end 0.12065 -0.2794)
			(stroke
				(width 0.1)
				(type default)
			)
			(layer "F.Fab")
		)
		(fp_line
			(start -0.12065 -0.305054)
			(end -0.12065 -0.2794)
			(stroke
				(width 0.1)
				(type default)
			)
			(layer "F.Fab")
		)
		(fp_line
			(start -0.67945 0.3048)
			(end -0.67945 -0.305054)
			(stroke
				(width 0.1)
				(type default)
			)
			(layer "F.Fab")
		)
		(fp_line
			(start -0.67945 -0.305054)
			(end -0.12065 -0.305054)
			(stroke
				(width 0.1)
				(type default)
			)
			(layer "F.Fab")
		)
		(pad "1" smd circle
			(at -0.40005 0 180)
			(size 0 0)
			(layers "F.Cu" "F.Mask" "F.Paste")
			(net "PVCCFA_EHV_CPU0_PVCC")
		)
		(pad "2" smd circle
			(at 0.40005 0 180)
			(size 0 0)
			(layers "F.Cu" "F.Mask" "F.Paste")
			(net "GND")
		)
	)
	(footprint ""
		(layer "F.Cu")
		(at 408.554682 -170.821858 180)
		(property "Reference" "PL4"
			(at 3.264662 3.982212 0)
			(unlocked yes)
			(layer "F.SilkS")
			(effects
				(font
					(size 0.7874 0.5842)
					(thickness 0.1524)
				)
				(justify left)
			)
		)
		(property "Value" ""
			(at 0 0 180)
			(layer "F.Fab")
			(effects
				(font
					(size 1.27 1.27)
				)
			)
		)
		(duplicate_pad_numbers_are_jumpers no)
		(fp_line
			(start 3.24993 3.24993)
			(end -3.24993 3.24993)
			(stroke
				(width 0.1524)
				(type default)
			)
			(layer "F.SilkS")
		)
		(fp_line
			(start 3.24993 2.2352)
			(end 3.24993 3.24993)
			(stroke
				(width 0.1524)
				(type default)
			)
			(layer "F.SilkS")
		)
		(fp_line
			(start 3.24993 -3.24993)
			(end 3.24993 -2.2352)
			(stroke
				(width 0.1524)
				(type default)
			)
			(layer "F.SilkS")
		)
		(fp_line
			(start -3.24993 3.24993)
			(end -3.24993 2.2352)
			(stroke
				(width 0.1524)
				(type default)
			)
			(layer "F.SilkS")
		)
		(fp_line
			(start -3.24993 -2.2352)
			(end -3.24993 -3.24993)
			(stroke
				(width 0.1524)
				(type default)
			)
			(layer "F.SilkS")
		)
		(fp_line
			(start -3.24993 -3.24993)
			(end 3.24993 -3.24993)
			(stroke
				(width 0.1524)
				(type default)
			)
			(layer "F.SilkS")
		)
		(fp_line
			(start 3.24993 3.24993)
			(end -3.24993 3.24993)
			(stroke
				(width 0.1)
				(type default)
			)
			(layer "F.Fab")
		)
		(fp_line
			(start 3.24993 -3.24993)
			(end 3.24993 3.24993)
			(stroke
				(width 0.1)
				(type default)
			)
			(layer "F.Fab")
		)
		(fp_line
			(start -3.24993 3.24993)
			(end -3.24993 -3.24993)
			(stroke
				(width 0.1)
				(type default)
			)
			(layer "F.Fab")
		)
		(fp_line
			(start -3.24993 -3.24993)
			(end 3.24993 -3.24993)
			(stroke
				(width 0.1)
				(type default)
			)
			(layer "F.Fab")
		)
		(pad "1" smd rect
			(at -2.29997 0 180)
			(size 2.0066 4.2164)
			(layers "F.Cu" "F.Mask" "F.Paste")
			(net "SW_PVCCINFAON_CPU0_SW1")
		)
		(pad "2" smd rect
			(at 2.29997 0 180)
			(size 2.0066 4.2164)
			(layers "F.Cu" "F.Mask" "F.Paste")
			(net "PVCCINFAON_CPU0")
		)
	)
)
